# S9S_MB_2U (Grand Teton) — schematic netlist excerpt (pin names and nets, part order shuffled) for the footprints in the layout excerpt that follows; sources: Cadence DE-HDL packaged netlist, KiCad conversion of 03242023_DA0F0TMBIJ0_F0T_Motherboard_J_brd_V01_OCP.brd

PU288  MP5991GLUZ  MP5991GLU-Z IC  pkg LGA32_TH_0-5_5X5  page 302
  VOUT1  = P12V_AUX
  VOUT2  = P12V_AUX
  D_OC  = HSC_D_OC_2
  \on\  = HSC_ON
  GOK  = HSC_FAULT
  FLT_TYPE  = HSC_FLT_TYPE_2
  NC1  = HSC_NC1_2
  MODE  = HSC_MODE_2
  VIN1  = P12V_PSU
  VIN2  = P12V_PSU
  VIN3  = P12V_PSU
  VIN4  = P12V_PSU
  VIN5  = P12V_PSU
  VIN6  = P12V_PSU
  VIN7  = P12V_PSU
  VIN8  = P12V_PSU
  SCREF_OCWREF  = HSC_SCREF_2
  VTEMP  = HSC_VTEMP
  SS  = HSC_SS
  GND  = AGND_HSC
  VDD33  = HSC_VDD_R_2
  IMON  = HSC_IMON
  CS  = HSC_CS_2
  OCREF  = HSC_OCREF
  VOUT3  = P12V_AUX
  VOUT4  = P12V_AUX
  VOUT5  = P12V_AUX
  VOUT6  = P12V_AUX
  VOUT7  = P12V_AUX
  VOUT8  = P12V_AUX
  VOUT9  = P12V_AUX
  VOUT10  = P12V_AUX
  VIN9  = P12V_PSU

(kicad_pcb
	(version 20260206)
	(generator "pcbnew")
	(generator_version "10.0")
	(general
		(thickness 1.6)
		(legacy_teardrops no)
	)
	(paper "A4")
	(title_block
		(title "03242023_DA0F0TMBIJ0_F0T_Motherboard_J_brd_V01_OCP.brd")
		(comment 1 "Grand Teton / footprints 2497-2497 of 6105")
	)
	(layers
		(0 "F.Cu" signal "TOP")
		(4 "In1.Cu" signal "GND")
		(6 "In2.Cu" signal "IN1")
		(8 "In3.Cu" signal "GND1")
		(10 "In4.Cu" signal "IN2")
		(12 "In5.Cu" signal "GND2")
		(14 "In6.Cu" signal "IN3")
		(16 "In7.Cu" signal "GND3")
		(18 "In8.Cu" signal "VCC")
		(20 "In9.Cu" signal "VCC1")
		(22 "In10.Cu" signal "GND4")
		(24 "In11.Cu" signal "IN4")
		(26 "In12.Cu" signal "GND5")
		(28 "In13.Cu" signal "IN5")
		(30 "In14.Cu" signal "GND6")
		(32 "In15.Cu" signal "IN6")
		(34 "In16.Cu" signal "GND7")
		(2 "B.Cu" signal "BOTTOM")
		(9 "F.Adhes" user "F.Adhesive")
		(11 "B.Adhes" user "B.Adhesive")
		(13 "F.Paste" user "Package Geometry/Pastemask Top")
		(15 "B.Paste" user "Package Geometry/Pastemask Bottom")
		(5 "F.SilkS" user "Ref Des/Silkscreen Top")
		(7 "B.SilkS" user "Ref Des/Silkscreen Bottom")
		(1 "F.Mask" user "Board Geometry/Soldermask Top")
		(3 "B.Mask" user "Board Geometry/Soldermask Bottom")
		(17 "Dwgs.User" user "User.Drawings")
		(19 "Cmts.User" user "User.Comments")
		(21 "Eco1.User" user "User.Eco1")
		(23 "Eco2.User" user "User.Eco2")
		(25 "Edge.Cuts" user "Board Geometry/Outline")
		(27 "Margin" user)
		(31 "F.CrtYd" user "Package Geometry/Place Bound Top")
		(29 "B.CrtYd" user "Package Geometry/Place Bound Bottom")
		(35 "F.Fab" user "Ref Des/Assembly Top")
		(33 "B.Fab" user "Ref Des/Assembly Bottom")
	)
	(footprint ""
		(layer "F.Cu")
		(at 210.840066 -402.722842 180)
		(property "Reference" "PU288"
			(at 0.323596 8.166608 0)
			(unlocked yes)
			(layer "F.SilkS")
			(effects
				(font
					(size 0.7874 0.5842)
					(thickness 0.1524)
				)
			)
		)
		(property "Value" ""
			(at 0 0 180)
			(layer "F.Fab")
			(effects
				(font
					(size 1.27 1.27)
				)
			)
		)
		(duplicate_pad_numbers_are_jumpers no)
		(fp_line
			(start 2.567686 2.567686)
			(end 2.567686 -2.567686)
			(stroke
				(width 0.1524)
				(type default)
			)
			(layer "F.SilkS")
		)
		(fp_line
			(start 2.567686 -2.567686)
			(end -2.567686 -2.567686)
			(stroke
				(width 0.1524)
				(type default)
			)
			(layer "F.SilkS")
		)
		(fp_line
			(start -2.567686 2.567686)
			(end 2.567686 2.567686)
			(stroke
				(width 0.1524)
				(type default)
			)
			(layer "F.SilkS")
		)
		(fp_line
			(start -2.567686 -2.567686)
			(end -2.567686 2.567686)
			(stroke
				(width 0.1524)
				(type default)
			)
			(layer "F.SilkS")
		)
		(fp_poly
			(pts
				(xy -3.120898 -3.448558) (xy -2.761742 -2.370836) (xy -3.83921 -2.729992)
			)
			(stroke
				(width 0)
				(type default)
			)
			(fill yes)
			(layer "F.SilkS")
		)
		(fp_line
			(start 2.549906 2.549906)
			(end 2.549906 -2.549906)
			(stroke
				(width 0.1)
				(type default)
			)
			(layer "F.Fab")
		)
		(fp_line
			(start 2.549906 -2.549906)
			(end -2.549906 -2.549906)
			(stroke
				(width 0.1)
				(type default)
			)
			(layer "F.Fab")
		)
		(fp_line
			(start -2.549906 2.549906)
			(end 2.549906 2.549906)
			(stroke
				(width 0.1)
				(type default)
			)
			(layer "F.Fab")
		)
		(fp_line
			(start -2.549906 -2.549906)
			(end -2.549906 2.549906)
			(stroke
				(width 0.1)
				(type default)
			)
			(layer "F.Fab")
		)
		(fp_poly
			(pts
				(xy -3.806698 -2.25806) (xy -3.806698 -1.24206) (xy -2.790698 -1.75006)
			)
			(stroke
				(width 0)
				(type default)
			)
			(fill yes)
			(layer "F.Fab")
		)
		(pad "1" smd rect
			(at -2.250186 -1.75006 270)
			(size 0.254 0.3556)
			(layers "F.Cu" "F.Mask" "F.Paste")
			(net "P12V_AUX")
		)
		(pad "2" smd rect
			(at -2.237486 -1.249934 270)
			(size 0.254 0.381)
			(layers "F.Cu" "F.Mask" "F.Paste")
			(net "P12V_AUX")
		)
		(pad "3" smd rect
			(at -2.237486 -0.750062 270)
			(size 0.254 0.381)
			(layers "F.Cu" "F.Mask" "F.Paste")
			(net "HSC_D_OC_2")
		)
		(pad "4" smd rect
			(at -2.237486 -0.249936 270)
			(size 0.254 0.381)
			(layers "F.Cu" "F.Mask" "F.Paste")
			(net "HSC_ON")
		)
		(pad "5" smd rect
			(at -2.237486 0.249936 270)
			(size 0.254 0.381)
			(layers "F.Cu" "F.Mask" "F.Paste")
			(net "HSC_FAULT")
		)
		(pad "6" smd rect
			(at -2.237486 0.750062 270)
			(size 0.254 0.381)
			(layers "F.Cu" "F.Mask" "F.Paste")
			(net "HSC_FLT_TYPE_2")
		)
		(pad "7" smd rect
			(at -2.237486 1.249934 270)
			(size 0.254 0.381)
			(layers "F.Cu" "F.Mask" "F.Paste")
			(net "HSC_NC1_2")
		)
		(pad "8" smd rect
			(at -2.250186 1.75006 270)
			(size 0.254 0.3556)
			(layers "F.Cu" "F.Mask" "F.Paste")
			(net "HSC_MODE_2")
		)
		(pad "9" smd rect
			(at -1.75006 2.250186 180)
			(size 0.254 0.3556)
			(layers "F.Cu" "F.Mask" "F.Paste")
			(net "P12V_PSU")
		)
		(pad "10" smd rect
			(at -1.249934 2.237486 180)
			(size 0.254 0.381)
			(layers "F.Cu" "F.Mask" "F.Paste")
			(net "P12V_PSU")
		)
		(pad "11" smd rect
			(at -0.750062 2.237486 180)
			(size 0.254 0.381)
			(layers "F.Cu" "F.Mask" "F.Paste")
			(net "P12V_PSU")
		)
		(pad "12" smd rect
			(at -0.249936 2.237486 180)
			(size 0.254 0.381)
			(layers "F.Cu" "F.Mask" "F.Paste")
			(net "P12V_PSU")
		)
		(pad "13" smd rect
			(at 0.249936 2.237486 180)
			(size 0.254 0.381)
			(layers "F.Cu" "F.Mask" "F.Paste")
			(net "P12V_PSU")
		)
		(pad "14" smd rect
			(at 0.750062 2.237486 180)
			(size 0.254 0.381)
			(layers "F.Cu" "F.Mask" "F.Paste")
			(net "P12V_PSU")
		)
		(pad "15" smd rect
			(at 1.249934 2.237486 180)
			(size 0.254 0.381)
			(layers "F.Cu" "F.Mask" "F.Paste")
			(net "P12V_PSU")
		)
		(pad "16" smd rect
			(at 1.75006 2.250186 180)
			(size 0.254 0.3556)
			(layers "F.Cu" "F.Mask" "F.Paste")
			(net "P12V_PSU")
		)
		(pad "17" smd rect
			(at 2.250186 1.75006 270)
			(size 0.254 0.3556)
			(layers "F.Cu" "F.Mask" "F.Paste")
			(net "HSC_SCREF_2")
		)
		(pad "18" smd rect
			(at 2.237486 1.249934 270)
			(size 0.254 0.381)
			(layers "F.Cu" "F.Mask" "F.Paste")
			(net "HSC_VTEMP")
		)
		(pad "19" smd rect
			(at 2.237486 0.750062 270)
			(size 0.254 0.381)
			(layers "F.Cu" "F.Mask" "F.Paste")
			(net "HSC_SS")
		)
		(pad "20" smd rect
			(at 2.237486 0.249936 270)
			(size 0.254 0.381)
			(layers "F.Cu" "F.Mask" "F.Paste")
			(net "AGND_HSC")
		)
		(pad "21" smd rect
			(at 2.237486 -0.249936 270)
			(size 0.254 0.381)
			(layers "F.Cu" "F.Mask" "F.Paste")
			(net "HSC_VDD_R_2")
		)
		(pad "22" smd rect
			(at 2.237486 -0.750062 270)
			(size 0.254 0.381)
			(layers "F.Cu" "F.Mask" "F.Paste")
			(net "HSC_IMON")
		)
		(pad "23" smd rect
			(at 2.237486 -1.249934 270)
			(size 0.254 0.381)
			(layers "F.Cu" "F.Mask" "F.Paste")
			(net "HSC_CS_2")
		)
		(pad "24" smd rect
			(at 2.250186 -1.75006 270)
			(size 0.254 0.3556)
			(layers "F.Cu" "F.Mask" "F.Paste")
			(net "HSC_OCREF")
		)
		(pad "25" smd rect
			(at 1.75006 -2.250186 180)
			(size 0.254 0.3556)
			(layers "F.Cu" "F.Mask" "F.Paste")
			(net "P12V_AUX")
		)
		(pad "26" smd rect
			(at 1.249934 -2.237486 180)
			(size 0.254 0.381)
			(layers "F.Cu" "F.Mask" "F.Paste")
			(net "P12V_AUX")
		)
		(pad "27" smd rect
			(at 0.750062 -2.237486 180)
			(size 0.254 0.381)
			(layers "F.Cu" "F.Mask" "F.Paste")
			(net "P12V_AUX")
		)
		(pad "28" smd rect
			(at 0.249936 -2.237486 180)
			(size 0.254 0.381)
			(layers "F.Cu" "F.Mask" "F.Paste")
			(net "P12V_AUX")
		)
		(pad "29" smd rect
			(at -0.249936 -2.237486 180)
			(size 0.254 0.381)
			(layers "F.Cu" "F.Mask" "F.Paste")
			(net "P12V_AUX")
		)
		(pad "30" smd rect
			(at -0.750062 -2.237486 180)
			(size 0.254 0.381)
			(layers "F.Cu" "F.Mask" "F.Paste")
			(net "P12V_AUX")
		)
		(pad "31" smd rect
			(at -1.249934 -2.237486 180)
			(size 0.254 0.381)
			(layers "F.Cu" "F.Mask" "F.Paste")
			(net "P12V_AUX")
		)
		(pad "32" smd rect
			(at -1.75006 -2.250186 180)
			(size 0.254 0.3556)
			(layers "F.Cu" "F.Mask" "F.Paste")
			(net "P12V_AUX")
		)
		(pad "33" smd rect
			(at 0 0 180)
			(size 3.4036 3.4036)
			(layers "F.Cu" "F.Mask" "F.Paste")
			(net "P12V_PSU")
		)
		(zone
			(layer "F.Cu")
			(hatch none 0.5)
			(connect_pads
				(clearance 0)
			)
			(min_thickness 0.25)
			(keepout
				(tracks not_allowed)
				(vias allowed)
				(pads allowed)
				(copperpour not_allowed)
				(footprints allowed)
			)
			(placement
				(enabled no)
				(sheetname "")
			)
			(fill
				(thermal_gap 0.5)
				(thermal_bridge_width 0.5)
				(island_removal_mode 0)
			)
			(polygon
				(pts
					(xy 212.861652 -401.275042) (xy 212.861652 -400.815048) (xy 212.74786 -400.701256) (xy 212.287866 -400.701256)
					(xy 212.287866 -400.726656) (xy 209.392266 -400.726656) (xy 209.392266 -400.701256) (xy 208.81848 -400.701256)
					(xy 208.81848 -401.275042) (xy 208.84388 -401.275042) (xy 208.84388 -404.170642) (xy 208.81848 -404.170642)
					(xy 208.81848 -404.475442) (xy 209.087466 -404.475442) (xy 209.087466 -400.970242) (xy 212.592666 -400.970242)
					(xy 212.592666 -403.230842) (xy 212.836252 -403.230842) (xy 212.836252 -401.275042)
				)
			)
		)
	)
)
